(kicad_pcb
	(version 20260206)
	(generator "pcbnew")
	(generator_version "10.0")
	(general
		(thickness 1.6)
		(legacy_teardrops no)
	)
	(paper "A4")
	(title_block
		(title "Bryce Canyon_SCC_16316-1_OCP.brd")
		(comment 1 "Bryce Canyon / footprints 326-333 of 1561")
	)
	(layers
		(0 "F.Cu" signal "TOP")
		(4 "In1.Cu" signal "L2GND")
		(6 "In2.Cu" signal "L3")
		(8 "In3.Cu" signal "L4VCC")
		(10 "In4.Cu" signal "L5VCC")
		(12 "In5.Cu" signal "L6")
		(14 "In6.Cu" signal "L7GND")
		(2 "B.Cu" signal "BOTTOM")
		(9 "F.Adhes" user "F.Adhesive")
		(11 "B.Adhes" user "B.Adhesive")
		(13 "F.Paste" user "Package Geometry/Pastemask Top")
		(15 "B.Paste" user "Package Geometry/Pastemask Bottom")
		(5 "F.SilkS" user "Ref Des/Silkscreen Top")
		(7 "B.SilkS" user "Ref Des/Silkscreen Bottom")
		(1 "F.Mask" user "Board Geometry/Soldermask Top")
		(3 "B.Mask" user "Board Geometry/Soldermask Bottom")
		(17 "Dwgs.User" user "User.Drawings")
		(19 "Cmts.User" user "User.Comments")
		(21 "Eco1.User" user "User.Eco1")
		(23 "Eco2.User" user "User.Eco2")
		(25 "Edge.Cuts" user "Board Geometry/Outline")
		(27 "Margin" user)
		(31 "F.CrtYd" user "Package Geometry/Place Bound Top")
		(29 "B.CrtYd" user "Package Geometry/Place Bound Bottom")
		(35 "F.Fab" user "Ref Des/Assembly Top")
		(33 "B.Fab" user "Ref Des/Assembly Bottom")
	)
	(footprint ""
		(layer "F.Cu")
		(at 7.2898 -75.3618 90)
		(property "Reference" "R358"
			(at 0 0 90)
			(layer "F.SilkS")
			(hide yes)
			(effects
				(font
					(size 1.27 1.27)
				)
			)
		)
		(property "Value" "4K7R2F-GP"
			(at 0.064008 -3.993896 90)
			(unlocked yes)
			(layer "F.Fab")
			(hide yes)
			(effects
				(font
					(size 1.016 1.016)
					(thickness 0.1524)
				)
			)
		)
		(property "Device Type" "R402H16"
			(at 0.064008 -5.517896 90)
			(unlocked yes)
			(layer "F.Fab")
			(hide yes)
			(effects
				(font
					(size 1.016 1.016)
					(thickness 0.1524)
				)
			)
		)
		(duplicate_pad_numbers_are_jumpers no)
		(fp_line
			(start 0.508 -0.9398)
			(end -0.508 -0.9398)
			(stroke
				(width 0.1524)
				(type default)
			)
			(layer "F.SilkS")
		)
		(fp_line
			(start -0.508 -0.9398)
			(end -0.508 0.9398)
			(stroke
				(width 0.1524)
				(type default)
			)
			(layer "F.SilkS")
		)
		(fp_rect
			(start -0.508 0.9398)
			(end 0.508 -0.9398)
			(stroke
				(width 0)
				(type default)
			)
			(fill no)
			(layer "F.CrtYd")
		)
		(fp_rect
			(start -0.508 0.9398)
			(end 0.508 -0.9398)
			(stroke
				(width 0)
				(type default)
			)
			(fill no)
			(layer "F.Fab")
		)
		(pad "1" smd custom
			(at 0 -0.4445 90)
			(size 0.1397 0.1397)
			(layers "F.Cu" "F.Mask" "F.Paste")
			(net "P3V3")
			(options
				(clearance outline)
				(anchor circle)
			)
			(primitives
				(gr_poly
					(pts
						(arc
							(start -0.1778 -0.2794)
							(mid -0.249642 -0.249642)
							(end -0.2794 -0.1778)
						)
						(arc
							(start -0.2794 0.1778)
							(mid -0.249642 0.249642)
							(end -0.1778 0.2794)
						)
						(arc
							(start 0.1778 0.2794)
							(mid 0.249642 0.249642)
							(end 0.2794 0.1778)
						)
						(arc
							(start 0.2794 -0.1778)
							(mid 0.249642 -0.249642)
							(end 0.1778 -0.2794)
						)
					)
					(width 0)
					(fill yes)
				)
			)
		)
		(pad "2" smd custom
			(at 0 0.4445 90)
			(size 0.1397 0.1397)
			(layers "F.Cu" "F.Mask" "F.Paste")
			(net "FRU_EEPROM_A0")
			(options
				(clearance outline)
				(anchor circle)
			)
			(primitives
				(gr_poly
					(pts
						(arc
							(start -0.1778 -0.2794)
							(mid -0.249642 -0.249642)
							(end -0.2794 -0.1778)
						)
						(arc
							(start -0.2794 0.1778)
							(mid -0.249642 0.249642)
							(end -0.1778 0.2794)
						)
						(arc
							(start 0.1778 0.2794)
							(mid 0.249642 0.249642)
							(end 0.2794 0.1778)
						)
						(arc
							(start 0.2794 -0.1778)
							(mid 0.249642 -0.249642)
							(end 0.1778 -0.2794)
						)
					)
					(width 0)
					(fill yes)
				)
			)
		)
	)
	(footprint ""
		(layer "F.Cu")
		(at 157.861 -120.523)
		(property "Reference" "R320"
			(at 0 0 0)
			(layer "F.SilkS")
			(hide yes)
			(effects
				(font
					(size 1.27 1.27)
				)
			)
		)
		(property "Value" "69K8R2F-GP"
			(at 0.064008 -3.993896 0)
			(unlocked yes)
			(layer "F.Fab")
			(hide yes)
			(effects
				(font
					(size 1.016 1.016)
					(thickness 0.1524)
				)
			)
		)
		(property "Device Type" "R402H16"
			(at 0.064008 -5.517896 0)
			(unlocked yes)
			(layer "F.Fab")
			(hide yes)
			(effects
				(font
					(size 1.016 1.016)
					(thickness 0.1524)
				)
			)
		)
		(duplicate_pad_numbers_are_jumpers no)
		(fp_line
			(start -0.508 -0.9398)
			(end -0.508 0.9398)
			(stroke
				(width 0.1524)
				(type default)
			)
			(layer "F.SilkS")
		)
		(fp_line
			(start 0.508 -0.9398)
			(end -0.508 -0.9398)
			(stroke
				(width 0.1524)
				(type default)
			)
			(layer "F.SilkS")
		)
		(fp_rect
			(start -0.508 0.9398)
			(end 0.508 -0.9398)
			(stroke
				(width 0)
				(type default)
			)
			(fill no)
			(layer "F.CrtYd")
		)
		(fp_rect
			(start -0.508 0.9398)
			(end 0.508 -0.9398)
			(stroke
				(width 0)
				(type default)
			)
			(fill no)
			(layer "F.Fab")
		)
		(pad "1" smd custom
			(at 0 -0.4445)
			(size 0.1397 0.1397)
			(layers "F.Cu" "F.Mask" "F.Paste")
			(net "AGND_P1V5_E")
			(options
				(clearance outline)
				(anchor circle)
			)
			(primitives
				(gr_poly
					(pts
						(arc
							(start -0.1778 -0.2794)
							(mid -0.249642 -0.249642)
							(end -0.2794 -0.1778)
						)
						(arc
							(start -0.2794 0.1778)
							(mid -0.249642 0.249642)
							(end -0.1778 0.2794)
						)
						(arc
							(start 0.1778 0.2794)
							(mid 0.249642 0.249642)
							(end 0.2794 0.1778)
						)
						(arc
							(start 0.2794 -0.1778)
							(mid 0.249642 -0.249642)
							(end 0.1778 -0.2794)
						)
					)
					(width 0)
					(fill yes)
				)
			)
		)
		(pad "2" smd custom
			(at 0 0.4445)
			(size 0.1397 0.1397)
			(layers "F.Cu" "F.Mask" "F.Paste")
			(net "P1V5_E_TRIP")
			(options
				(clearance outline)
				(anchor circle)
			)
			(primitives
				(gr_poly
					(pts
						(arc
							(start -0.1778 -0.2794)
							(mid -0.249642 -0.249642)
							(end -0.2794 -0.1778)
						)
						(arc
							(start -0.2794 0.1778)
							(mid -0.249642 0.249642)
							(end -0.1778 0.2794)
						)
						(arc
							(start 0.1778 0.2794)
							(mid 0.249642 0.249642)
							(end 0.2794 0.1778)
						)
						(arc
							(start 0.2794 -0.1778)
							(mid 0.249642 -0.249642)
							(end 0.1778 -0.2794)
						)
					)
					(width 0)
					(fill yes)
				)
			)
		)
	)
	(footprint ""
		(layer "F.Cu")
		(at 174.4726 -59.817)
		(property "Reference" "R253"
			(at 0 0 0)
			(layer "F.SilkS")
			(hide yes)
			(effects
				(font
					(size 1.27 1.27)
				)
			)
		)
		(property "Value" "10KR2F-2-GP"
			(at 0.064008 -3.993896 0)
			(unlocked yes)
			(layer "F.Fab")
			(hide yes)
			(effects
				(font
					(size 1.016 1.016)
					(thickness 0.1524)
				)
			)
		)
		(property "Device Type" "R402H16"
			(at 0.064008 -5.517896 0)
			(unlocked yes)
			(layer "F.Fab")
			(hide yes)
			(effects
				(font
					(size 1.016 1.016)
					(thickness 0.1524)
				)
			)
		)
		(duplicate_pad_numbers_are_jumpers no)
		(fp_line
			(start -0.508 -0.9398)
			(end -0.508 0.9398)
			(stroke
				(width 0.1524)
				(type default)
			)
			(layer "F.SilkS")
		)
		(fp_line
			(start 0.508 -0.9398)
			(end -0.508 -0.9398)
			(stroke
				(width 0.1524)
				(type default)
			)
			(layer "F.SilkS")
		)
		(fp_rect
			(start -0.508 0.9398)
			(end 0.508 -0.9398)
			(stroke
				(width 0)
				(type default)
			)
			(fill no)
			(layer "F.CrtYd")
		)
		(fp_rect
			(start -0.508 0.9398)
			(end 0.508 -0.9398)
			(stroke
				(width 0)
				(type default)
			)
			(fill no)
			(layer "F.Fab")
		)
		(pad "1" smd custom
			(at 0 -0.4445)
			(size 0.1397 0.1397)
			(layers "F.Cu" "F.Mask" "F.Paste")
			(net "P1V8_C")
			(options
				(clearance outline)
				(anchor circle)
			)
			(primitives
				(gr_poly
					(pts
						(arc
							(start -0.1778 -0.2794)
							(mid -0.249642 -0.249642)
							(end -0.2794 -0.1778)
						)
						(arc
							(start -0.2794 0.1778)
							(mid -0.249642 0.249642)
							(end -0.1778 0.2794)
						)
						(arc
							(start 0.1778 0.2794)
							(mid 0.249642 0.249642)
							(end 0.2794 0.1778)
						)
						(arc
							(start 0.2794 -0.1778)
							(mid 0.249642 -0.249642)
							(end 0.1778 -0.2794)
						)
					)
					(width 0)
					(fill yes)
				)
			)
		)
		(pad "2" smd custom
			(at 0 0.4445)
			(size 0.1397 0.1397)
			(layers "F.Cu" "F.Mask" "F.Paste")
			(net "LSI_JTAG_EN_N")
			(options
				(clearance outline)
				(anchor circle)
			)
			(primitives
				(gr_poly
					(pts
						(arc
							(start -0.1778 -0.2794)
							(mid -0.249642 -0.249642)
							(end -0.2794 -0.1778)
						)
						(arc
							(start -0.2794 0.1778)
							(mid -0.249642 0.249642)
							(end -0.1778 0.2794)
						)
						(arc
							(start 0.1778 0.2794)
							(mid 0.249642 0.249642)
							(end 0.2794 0.1778)
						)
						(arc
							(start 0.2794 -0.1778)
							(mid 0.249642 -0.249642)
							(end 0.1778 -0.2794)
						)
					)
					(width 0)
					(fill yes)
				)
			)
		)
	)
	(footprint ""
		(layer "F.Cu")
		(at 9.24687 -47.248318)
		(property "Reference" "R436"
			(at 0 0 0)
			(layer "F.SilkS")
			(hide yes)
			(effects
				(font
					(size 1.27 1.27)
				)
			)
		)
		(property "Value" "100R2D-GP"
			(at 0.064008 -3.993896 0)
			(unlocked yes)
			(layer "F.Fab")
			(hide yes)
			(effects
				(font
					(size 1.016 1.016)
					(thickness 0.1524)
				)
			)
		)
		(property "Device Type" "R402H14"
			(at 0.064008 -5.517896 0)
			(unlocked yes)
			(layer "F.Fab")
			(hide yes)
			(effects
				(font
					(size 1.016 1.016)
					(thickness 0.1524)
				)
			)
		)
		(duplicate_pad_numbers_are_jumpers no)
		(fp_line
			(start -0.508 -0.9398)
			(end -0.508 0.9398)
			(stroke
				(width 0.1524)
				(type default)
			)
			(layer "F.SilkS")
		)
		(fp_line
			(start 0.508 -0.9398)
			(end -0.508 -0.9398)
			(stroke
				(width 0.1524)
				(type default)
			)
			(layer "F.SilkS")
		)
		(fp_rect
			(start -0.508 0.9398)
			(end 0.508 -0.9398)
			(stroke
				(width 0)
				(type default)
			)
			(fill no)
			(layer "F.CrtYd")
		)
		(fp_rect
			(start -0.508 0.9398)
			(end 0.508 -0.9398)
			(stroke
				(width 0)
				(type default)
			)
			(fill no)
			(layer "F.Fab")
		)
		(pad "1" smd custom
			(at 0 -0.4445)
			(size 0.1397 0.1397)
			(layers "F.Cu" "F.Mask" "F.Paste")
			(net "MB0_TEMP")
			(options
				(clearance outline)
				(anchor circle)
			)
			(primitives
				(gr_poly
					(pts
						(arc
							(start -0.1778 -0.2794)
							(mid -0.249642 -0.249642)
							(end -0.2794 -0.1778)
						)
						(arc
							(start -0.2794 0.1778)
							(mid -0.249642 0.249642)
							(end -0.1778 0.2794)
						)
						(arc
							(start 0.1778 0.2794)
							(mid 0.249642 0.249642)
							(end 0.2794 0.1778)
						)
						(arc
							(start 0.2794 -0.1778)
							(mid 0.249642 -0.249642)
							(end 0.1778 -0.2794)
						)
					)
					(width 0)
					(fill yes)
				)
			)
		)
		(pad "2" smd custom
			(at 0 0.4445)
			(size 0.1397 0.1397)
			(layers "F.Cu" "F.Mask" "F.Paste")
			(net "MB0_TEMP_C")
			(options
				(clearance outline)
				(anchor circle)
			)
			(primitives
				(gr_poly
					(pts
						(arc
							(start -0.1778 -0.2794)
							(mid -0.249642 -0.249642)
							(end -0.2794 -0.1778)
						)
						(arc
							(start -0.2794 0.1778)
							(mid -0.249642 0.249642)
							(end -0.1778 0.2794)
						)
						(arc
							(start 0.1778 0.2794)
							(mid 0.249642 0.249642)
							(end 0.2794 0.1778)
						)
						(arc
							(start 0.2794 -0.1778)
							(mid 0.249642 -0.249642)
							(end 0.1778 -0.2794)
						)
					)
					(width 0)
					(fill yes)
				)
			)
		)
	)
	(footprint ""
		(layer "F.Cu")
		(at 9.7028 -93.6244)
		(property "Reference" "R413"
			(at 0 0 0)
			(layer "F.SilkS")
			(hide yes)
			(effects
				(font
					(size 1.27 1.27)
				)
			)
		)
		(property "Value" "1KR2F-3-GP"
			(at 0.064008 -3.993896 0)
			(unlocked yes)
			(layer "F.Fab")
			(hide yes)
			(effects
				(font
					(size 1.016 1.016)
					(thickness 0.1524)
				)
			)
		)
		(property "Device Type" "R402H16"
			(at 0.064008 -5.517896 0)
			(unlocked yes)
			(layer "F.Fab")
			(hide yes)
			(effects
				(font
					(size 1.016 1.016)
					(thickness 0.1524)
				)
			)
		)
		(duplicate_pad_numbers_are_jumpers no)
		(fp_line
			(start -0.508 -0.9398)
			(end -0.508 0.9398)
			(stroke
				(width 0.1524)
				(type default)
			)
			(layer "F.SilkS")
		)
		(fp_line
			(start 0.508 -0.9398)
			(end -0.508 -0.9398)
			(stroke
				(width 0.1524)
				(type default)
			)
			(layer "F.SilkS")
		)
		(fp_rect
			(start -0.508 0.9398)
			(end 0.508 -0.9398)
			(stroke
				(width 0)
				(type default)
			)
			(fill no)
			(layer "F.CrtYd")
		)
		(fp_rect
			(start -0.508 0.9398)
			(end 0.508 -0.9398)
			(stroke
				(width 0)
				(type default)
			)
			(fill no)
			(layer "F.Fab")
		)
		(pad "1" smd custom
			(at 0 -0.4445)
			(size 0.1397 0.1397)
			(layers "F.Cu" "F.Mask" "F.Paste")
			(net "P3V3")
			(options
				(clearance outline)
				(anchor circle)
			)
			(primitives
				(gr_poly
					(pts
						(arc
							(start -0.1778 -0.2794)
							(mid -0.249642 -0.249642)
							(end -0.2794 -0.1778)
						)
						(arc
							(start -0.2794 0.1778)
							(mid -0.249642 0.249642)
							(end -0.1778 0.2794)
						)
						(arc
							(start 0.1778 0.2794)
							(mid 0.249642 0.249642)
							(end 0.2794 0.1778)
						)
						(arc
							(start 0.2794 -0.1778)
							(mid 0.249642 -0.249642)
							(end 0.1778 -0.2794)
						)
					)
					(width 0)
					(fill yes)
				)
			)
		)
		(pad "2" smd custom
			(at 0 0.4445)
			(size 0.1397 0.1397)
			(layers "F.Cu" "F.Mask" "F.Paste")
			(net "I2C_SCC_SDA2")
			(options
				(clearance outline)
				(anchor circle)
			)
			(primitives
				(gr_poly
					(pts
						(arc
							(start -0.1778 -0.2794)
							(mid -0.249642 -0.249642)
							(end -0.2794 -0.1778)
						)
						(arc
							(start -0.2794 0.1778)
							(mid -0.249642 0.249642)
							(end -0.1778 0.2794)
						)
						(arc
							(start 0.1778 0.2794)
							(mid 0.249642 0.249642)
							(end 0.2794 0.1778)
						)
						(arc
							(start 0.2794 -0.1778)
							(mid 0.249642 -0.249642)
							(end 0.1778 -0.2794)
						)
					)
					(width 0)
					(fill yes)
				)
			)
		)
	)
	(footprint ""
		(layer "F.Cu")
		(at 158.369 -83.224116 -90)
		(property "Reference" "C525"
			(at 0 0 270)
			(layer "F.SilkS")
			(hide yes)
			(effects
				(font
					(size 1.27 1.27)
				)
			)
		)
		(property "Value" "SCD1U16V2KX-3GP"
			(at 1.1811 -2.7051 270)
			(unlocked yes)
			(layer "F.Fab")
			(hide yes)
			(effects
				(font
					(size 1.016 1.016)
					(thickness 0.1524)
				)
			)
		)
		(property "Device Type" "C402H22"
			(at 1.1811 -4.2291 270)
			(unlocked yes)
			(layer "F.Fab")
			(hide yes)
			(effects
				(font
					(size 1.016 1.016)
					(thickness 0.1524)
				)
			)
		)
		(duplicate_pad_numbers_are_jumpers no)
		(fp_rect
			(start -0.4318 0.9525)
			(end 0.4318 -0.9525)
			(stroke
				(width 0)
				(type default)
			)
			(fill no)
			(layer "F.CrtYd")
		)
		(fp_rect
			(start -0.4318 0.9525)
			(end 0.4318 -0.9525)
			(stroke
				(width 0)
				(type default)
			)
			(fill no)
			(layer "F.Fab")
		)
		(pad "1" smd custom
			(at 0 -0.4445 270)
			(size 0.1524 0.1524)
			(layers "F.Cu" "F.Mask" "F.Paste")
			(net "P1V5_E_SENSE")
			(options
				(clearance outline)
				(anchor circle)
			)
			(primitives
				(gr_poly
					(pts
						(arc
							(start 0.3048 -0.2032)
							(mid 0.275042 -0.275042)
							(end 0.2032 -0.3048)
						)
						(arc
							(start -0.2032 -0.3048)
							(mid -0.275042 -0.275042)
							(end -0.3048 -0.2032)
						)
						(arc
							(start -0.3048 0.2032)
							(mid -0.275042 0.275042)
							(end -0.2032 0.3048)
						)
						(arc
							(start 0.2032 0.3048)
							(mid 0.275042 0.275042)
							(end 0.3048 0.2032)
						)
					)
					(width 0)
					(fill yes)
				)
			)
		)
		(pad "2" smd custom
			(at 0 0.4445 270)
			(size 0.1524 0.1524)
			(layers "F.Cu" "F.Mask" "F.Paste")
			(net "GND")
			(options
				(clearance outline)
				(anchor circle)
			)
			(primitives
				(gr_poly
					(pts
						(arc
							(start 0.3048 -0.2032)
							(mid 0.275042 -0.275042)
							(end 0.2032 -0.3048)
						)
						(arc
							(start -0.2032 -0.3048)
							(mid -0.275042 -0.275042)
							(end -0.3048 -0.2032)
						)
						(arc
							(start -0.3048 0.2032)
							(mid -0.275042 0.275042)
							(end -0.2032 0.3048)
						)
						(arc
							(start 0.2032 0.3048)
							(mid 0.275042 0.275042)
							(end 0.3048 0.2032)
						)
					)
					(width 0)
					(fill yes)
				)
			)
		)
	)
	(footprint ""
		(layer "F.Cu")
		(at 178.08448 -110.64748 180)
		(property "Reference" "C602"
			(at 0 0 180)
			(layer "F.SilkS")
			(hide yes)
			(effects
				(font
					(size 1.27 1.27)
				)
			)
		)
		(property "Value" "SC470P50V2KX-3GP"
			(at 1.1811 -2.7051 180)
			(unlocked yes)
			(layer "F.Fab")
			(hide yes)
			(effects
				(font
					(size 1.016 1.016)
					(thickness 0.1524)
				)
			)
		)
		(property "Device Type" "C402H22"
			(at 1.1811 -4.2291 180)
			(unlocked yes)
			(layer "F.Fab")
			(hide yes)
			(effects
				(font
					(size 1.016 1.016)
					(thickness 0.1524)
				)
			)
		)
		(duplicate_pad_numbers_are_jumpers no)
		(fp_rect
			(start -0.4318 0.9525)
			(end 0.4318 -0.9525)
			(stroke
				(width 0)
				(type default)
			)
			(fill no)
			(layer "F.CrtYd")
		)
		(fp_rect
			(start -0.4318 0.9525)
			(end 0.4318 -0.9525)
			(stroke
				(width 0)
				(type default)
			)
			(fill no)
			(layer "F.Fab")
		)
		(pad "1" smd custom
			(at 0 -0.4445 180)
			(size 0.1524 0.1524)
			(layers "F.Cu" "F.Mask" "F.Paste")
			(net "GND")
			(options
				(clearance outline)
				(anchor circle)
			)
			(primitives
				(gr_poly
					(pts
						(arc
							(start 0.3048 -0.2032)
							(mid 0.275042 -0.275042)
							(end 0.2032 -0.3048)
						)
						(arc
							(start -0.2032 -0.3048)
							(mid -0.275042 -0.275042)
							(end -0.3048 -0.2032)
						)
						(arc
							(start -0.3048 0.2032)
							(mid -0.275042 0.275042)
							(end -0.2032 0.3048)
						)
						(arc
							(start 0.2032 0.3048)
							(mid 0.275042 0.275042)
							(end 0.3048 0.2032)
						)
					)
					(width 0)
					(fill yes)
				)
			)
		)
		(pad "2" smd custom
			(at 0 0.4445 180)
			(size 0.1524 0.1524)
			(layers "F.Cu" "F.Mask" "F.Paste")
			(net "P1V8_E_SS")
			(options
				(clearance outline)
				(anchor circle)
			)
			(primitives
				(gr_poly
					(pts
						(arc
							(start 0.3048 -0.2032)
							(mid 0.275042 -0.275042)
							(end 0.2032 -0.3048)
						)
						(arc
							(start -0.2032 -0.3048)
							(mid -0.275042 -0.275042)
							(end -0.3048 -0.2032)
						)
						(arc
							(start -0.3048 0.2032)
							(mid -0.275042 0.275042)
							(end -0.2032 0.3048)
						)
						(arc
							(start 0.2032 0.3048)
							(mid 0.275042 0.275042)
							(end 0.3048 0.2032)
						)
					)
					(width 0)
					(fill yes)
				)
			)
		)
	)
	(footprint ""
		(layer "F.Cu")
		(at 178.181 -57.277)
		(property "Reference" "TP143"
			(at 0 0 0)
			(layer "F.SilkS")
			(hide yes)
			(effects
				(font
					(size 1.27 1.27)
				)
			)
		)
		(property "Value" "TPAD28-2-GP"
			(at -0.0127 -1.6637 0)
			(unlocked yes)
			(layer "F.Fab")
			(hide yes)
			(effects
				(font
					(size 1.016 1.016)
					(thickness 0.1524)
				)
			)
		)
		(property "Device Type" "TPAD28"
			(at -0.0127 -3.1877 0)
			(unlocked yes)
			(layer "F.Fab")
			(hide yes)
			(effects
				(font
					(size 1.016 1.016)
					(thickness 0.1524)
				)
			)
		)
		(duplicate_pad_numbers_are_jumpers no)
		(fp_poly
			(pts
				(arc
					(start 0.3556 0)
					(mid -0.3556 0)
					(end 0.3556 0)
				)
			)
			(stroke
				(width 0)
				(type default)
			)
			(fill no)
			(layer "F.CrtYd")
		)
		(fp_poly
			(pts
				(arc
					(start 0.6096 0)
					(mid -0.6096 0)
					(end 0.6096 0)
				)
			)
			(stroke
				(width 0)
				(type default)
			)
			(fill no)
			(layer "F.Fab")
		)
		(pad "1" smd circle
			(at 0 0)
			(size 0.7112 0.7112)
			(layers "F.Cu" "F.Mask" "F.Paste")
			(net "LSI_IDDT")
		)
	)
)
